# BASEBOARD_FAB2 (Tioga Pass) — schematic netlist excerpt (pin names and nets, part order shuffled) for the footprints in the layout excerpt that follows; sources: Cadence DE-HDL packaged netlist, KiCad conversion of Wiwynn_Tioga_Pass_MB.brd

C9L10  CAP  10UF 16V 10% X6S  pkg 0805  page 227 : A = VR_FET_SW_P12V_STBY_PVDDQ_KLM ; B = GND
R7C13  RES  10.0K 1% CHIP  pkg 0402  page 137 : A = P3V3_STBY ; B = FM_UART_PRES_N
R1L6  RES  0.0 5% CHIP  pkg 0402  page 168 : A = FM_UART_SWITCH_N ; B = FM_DB_UART_SEL0_N

(kicad_pcb
	(version 20260206)
	(generator "pcbnew")
	(generator_version "10.0")
	(general
		(thickness 1.6)
		(legacy_teardrops no)
	)
	(paper "A4")
	(title_block
		(title "Wiwynn_Tioga_Pass_MB.brd")
		(comment 1 "Tioga Pass / footprints 3450-3452 of 4770")
	)
	(layers
		(0 "F.Cu" signal "TOP")
		(4 "In1.Cu" signal "L2GND")
		(6 "In2.Cu" signal "L3")
		(8 "In3.Cu" signal "L4GND")
		(10 "In4.Cu" signal "L5")
		(12 "In5.Cu" signal "L6GND")
		(14 "In6.Cu" signal "L7VCC")
		(16 "In7.Cu" signal "L8VCC")
		(18 "In8.Cu" signal "L9GND")
		(20 "In9.Cu" signal "L10")
		(22 "In10.Cu" signal "L11GND")
		(24 "In11.Cu" signal "L12")
		(26 "In12.Cu" signal "L13GND")
		(2 "B.Cu" signal "BOTTOM")
		(9 "F.Adhes" user "F.Adhesive")
		(11 "B.Adhes" user "B.Adhesive")
		(13 "F.Paste" user "Package Geometry/Pastemask Top")
		(15 "B.Paste" user "Package Geometry/Pastemask Bottom")
		(5 "F.SilkS" user "Ref Des/Silkscreen Top")
		(7 "B.SilkS" user "Ref Des/Silkscreen Bottom")
		(1 "F.Mask" user "Board Geometry/Soldermask Top")
		(3 "B.Mask" user "Board Geometry/Soldermask Bottom")
		(17 "Dwgs.User" user "User.Drawings")
		(19 "Cmts.User" user "User.Comments")
		(21 "Eco1.User" user "User.Eco1")
		(23 "Eco2.User" user "User.Eco2")
		(25 "Edge.Cuts" user "Board Geometry/Outline")
		(27 "Margin" user)
		(31 "F.CrtYd" user "Package Geometry/Place Bound Top")
		(29 "B.CrtYd" user "Package Geometry/Place Bound Bottom")
		(35 "F.Fab" user "Ref Des/Assembly Top")
		(33 "B.Fab" user "Ref Des/Assembly Bottom")
	)
	(footprint ""
		(layer "B.Cu")
		(at 487.1085 -151.6126 90)
		(property "Reference" "R1L6"
			(at 0 0 90)
			(layer "B.SilkS")
			(hide yes)
			(effects
				(font
					(size 1.27 1.27)
				)
				(justify mirror)
			)
		)
		(property "Value" ""
			(at 0 0 90)
			(layer "B.Fab")
			(effects
				(font
					(size 1.27 1.27)
				)
				(justify mirror)
			)
		)
		(duplicate_pad_numbers_are_jumpers no)
		(fp_poly
			(pts
				(xy 0.2794 -0.1016) (xy -0.2794 -0.1016) (xy -0.2794 0.9906) (xy 0.2794 0.9906)
			)
			(stroke
				(width 0)
				(type default)
			)
			(fill no)
			(layer "B.CrtYd")
		)
		(fp_line
			(start 0.2794 -0.1016)
			(end 0.2794 0.9906)
			(stroke
				(width 0.1)
				(type default)
			)
			(layer "B.Fab")
		)
		(fp_line
			(start -0.2794 -0.1016)
			(end 0.2794 -0.1016)
			(stroke
				(width 0.1)
				(type default)
			)
			(layer "B.Fab")
		)
		(fp_line
			(start 0.2794 0.9906)
			(end -0.2794 0.9906)
			(stroke
				(width 0.1)
				(type default)
			)
			(layer "B.Fab")
		)
		(fp_line
			(start -0.2794 0.9906)
			(end -0.2794 -0.1016)
			(stroke
				(width 0.1)
				(type default)
			)
			(layer "B.Fab")
		)
		(pad "1" smd rect
			(at 0 0 270)
			(size 0.508 0.508)
			(layers "B.Cu" "B.Mask" "B.Paste")
			(net "FM_UART_SWITCH_N")
		)
		(pad "2" smd rect
			(at 0 0.889 270)
			(size 0.508 0.508)
			(layers "B.Cu" "B.Mask" "B.Paste")
			(net "FM_DB_UART_SEL0_N")
		)
		(zone
			(layer "B.Cu")
			(hatch none 0.5)
			(connect_pads
				(clearance 0)
			)
			(min_thickness 0.25)
			(keepout
				(tracks allowed)
				(vias not_allowed)
				(pads allowed)
				(copperpour not_allowed)
				(footprints allowed)
			)
			(placement
				(enabled no)
				(sheetname "")
			)
			(fill
				(thermal_gap 0.5)
				(thermal_bridge_width 0.5)
				(island_removal_mode 0)
			)
			(polygon
				(pts
					(xy 487.3625 -151.8666) (xy 487.3625 -151.3586) (xy 487.7435 -151.3586) (xy 487.7435 -151.8666)
				)
			)
		)
		(zone
			(layer "B.Cu")
			(hatch none 0.5)
			(connect_pads
				(clearance 0)
			)
			(min_thickness 0.25)
			(keepout
				(tracks not_allowed)
				(vias allowed)
				(pads allowed)
				(copperpour not_allowed)
				(footprints allowed)
			)
			(placement
				(enabled no)
				(sheetname "")
			)
			(fill
				(thermal_gap 0.5)
				(thermal_bridge_width 0.5)
				(island_removal_mode 0)
			)
			(polygon
				(pts
					(xy 487.7435 -151.8666) (xy 487.7435 -151.3586) (xy 487.3625 -151.3586) (xy 487.3625 -151.8666)
				)
			)
		)
	)
	(footprint ""
		(layer "B.Cu")
		(at 380.746 -87.3125 180)
		(property "Reference" "R7C13"
			(at 0 0 0)
			(layer "B.SilkS")
			(hide yes)
			(effects
				(font
					(size 1.27 1.27)
				)
				(justify mirror)
			)
		)
		(property "Value" ""
			(at 0 0 0)
			(layer "B.Fab")
			(effects
				(font
					(size 1.27 1.27)
				)
				(justify mirror)
			)
		)
		(duplicate_pad_numbers_are_jumpers no)
		(fp_poly
			(pts
				(xy 0.2794 -0.1016) (xy -0.2794 -0.1016) (xy -0.2794 0.9906) (xy 0.2794 0.9906)
			)
			(stroke
				(width 0)
				(type default)
			)
			(fill no)
			(layer "B.CrtYd")
		)
		(fp_line
			(start 0.2794 0.9906)
			(end -0.2794 0.9906)
			(stroke
				(width 0.1)
				(type default)
			)
			(layer "B.Fab")
		)
		(fp_line
			(start 0.2794 -0.1016)
			(end 0.2794 0.9906)
			(stroke
				(width 0.1)
				(type default)
			)
			(layer "B.Fab")
		)
		(fp_line
			(start -0.2794 0.9906)
			(end -0.2794 -0.1016)
			(stroke
				(width 0.1)
				(type default)
			)
			(layer "B.Fab")
		)
		(fp_line
			(start -0.2794 -0.1016)
			(end 0.2794 -0.1016)
			(stroke
				(width 0.1)
				(type default)
			)
			(layer "B.Fab")
		)
		(pad "1" smd rect
			(at 0 0)
			(size 0.508 0.508)
			(layers "B.Cu" "B.Mask" "B.Paste")
			(net "P3V3_STBY")
		)
		(pad "2" smd rect
			(at 0 0.889)
			(size 0.508 0.508)
			(layers "B.Cu" "B.Mask" "B.Paste")
			(net "FM_UART_PRES_N")
		)
		(zone
			(layer "B.Cu")
			(hatch none 0.5)
			(connect_pads
				(clearance 0)
			)
			(min_thickness 0.25)
			(keepout
				(tracks not_allowed)
				(vias allowed)
				(pads allowed)
				(copperpour not_allowed)
				(footprints allowed)
			)
			(placement
				(enabled no)
				(sheetname "")
			)
			(fill
				(thermal_gap 0.5)
				(thermal_bridge_width 0.5)
				(island_removal_mode 0)
			)
			(polygon
				(pts
					(xy 380.492 -87.9475) (xy 381 -87.9475) (xy 381 -87.5665) (xy 380.492 -87.5665)
				)
			)
		)
		(zone
			(layer "B.Cu")
			(hatch none 0.5)
			(connect_pads
				(clearance 0)
			)
			(min_thickness 0.25)
			(keepout
				(tracks allowed)
				(vias not_allowed)
				(pads allowed)
				(copperpour not_allowed)
				(footprints allowed)
			)
			(placement
				(enabled no)
				(sheetname "")
			)
			(fill
				(thermal_gap 0.5)
				(thermal_bridge_width 0.5)
				(island_removal_mode 0)
			)
			(polygon
				(pts
					(xy 380.492 -87.5665) (xy 381 -87.5665) (xy 381 -87.9475) (xy 380.492 -87.9475)
				)
			)
		)
	)
	(footprint ""
		(layer "B.Cu")
		(at 1.3462 -137.795 90)
		(property "Reference" "C9L10"
			(at 0 0 90)
			(layer "B.SilkS")
			(hide yes)
			(effects
				(font
					(size 1.27 1.27)
				)
				(justify mirror)
			)
		)
		(property "Value" ""
			(at 0 0 90)
			(layer "B.Fab")
			(effects
				(font
					(size 1.27 1.27)
				)
				(justify mirror)
			)
		)
		(duplicate_pad_numbers_are_jumpers no)
		(fp_rect
			(start -0.7239 -0.2159)
			(end 0.7239 1.9939)
			(stroke
				(width 0)
				(type default)
			)
			(fill no)
			(layer "B.CrtYd")
		)
		(fp_line
			(start 0.7239 -0.2159)
			(end 0.7239 1.9939)
			(stroke
				(width 0.1)
				(type default)
			)
			(layer "B.Fab")
		)
		(fp_line
			(start -0.7239 -0.2159)
			(end 0.7239 -0.2159)
			(stroke
				(width 0.1)
				(type default)
			)
			(layer "B.Fab")
		)
		(fp_line
			(start 0.7239 1.9939)
			(end -0.7239 1.9939)
			(stroke
				(width 0.1)
				(type default)
			)
			(layer "B.Fab")
		)
		(fp_line
			(start -0.7239 1.9939)
			(end -0.7239 -0.2159)
			(stroke
				(width 0.1)
				(type default)
			)
			(layer "B.Fab")
		)
		(pad "1" smd rect
			(at 0 0 270)
			(size 1.27 1.016)
			(layers "B.Cu" "B.Mask" "B.Paste")
			(net "VR_FET_SW_P12V_STBY_PVDDQ_KLM")
		)
		(pad "2" smd rect
			(at 0 1.778 270)
			(size 1.27 1.016)
			(layers "B.Cu" "B.Mask" "B.Paste")
			(net "GND")
		)
		(zone
			(layer "B.Cu")
			(hatch none 0.5)
			(connect_pads
				(clearance 0)
			)
			(min_thickness 0.25)
			(keepout
				(tracks not_allowed)
				(vias allowed)
				(pads allowed)
				(copperpour not_allowed)
				(footprints allowed)
			)
			(placement
				(enabled no)
				(sheetname "")
			)
			(fill
				(thermal_gap 0.5)
				(thermal_bridge_width 0.5)
				(island_removal_mode 0)
			)
			(polygon
				(pts
					(xy 1.8542 -137.16) (xy 2.6162 -137.16) (xy 2.6162 -138.43) (xy 1.8542 -138.43)
				)
			)
		)
	)
)
